(kicad_pcb
	(version 20260206)
	(generator "pcbnew")
	(generator_version "10.0")
	(general
		(thickness 1.6)
		(legacy_teardrops no)
	)
	(paper "A4")
	(title_block
		(title "baseboard — 13948-1b.1110WZS1818.brd")
		(comment 1 "Honey Badger (Wiwynn) / footprints 2205-2212 of 2523")
	)
	(layers
		(0 "F.Cu" signal "TOP")
		(4 "In1.Cu" signal "L2GND")
		(6 "In2.Cu" signal "L3")
		(8 "In3.Cu" signal "L4VCC")
		(10 "In4.Cu" signal "L5VCC")
		(12 "In5.Cu" signal "L6")
		(14 "In6.Cu" signal "L7GND")
		(2 "B.Cu" signal "BOTTOM")
		(9 "F.Adhes" user "F.Adhesive")
		(11 "B.Adhes" user "B.Adhesive")
		(13 "F.Paste" user "Package Geometry/Pastemask Top")
		(15 "B.Paste" user "Package Geometry/Pastemask Bottom")
		(5 "F.SilkS" user "Ref Des/Silkscreen Top")
		(7 "B.SilkS" user "Ref Des/Silkscreen Bottom")
		(1 "F.Mask" user "Board Geometry/Soldermask Top")
		(3 "B.Mask" user "Board Geometry/Soldermask Bottom")
		(17 "Dwgs.User" user "User.Drawings")
		(19 "Cmts.User" user "User.Comments")
		(21 "Eco1.User" user "User.Eco1")
		(23 "Eco2.User" user "User.Eco2")
		(25 "Edge.Cuts" user "Board Geometry/Outline")
		(27 "Margin" user)
		(31 "F.CrtYd" user "Package Geometry/Place Bound Top")
		(29 "B.CrtYd" user "Package Geometry/Place Bound Bottom")
		(35 "F.Fab" user "Ref Des/Assembly Top")
		(33 "B.Fab" user "Ref Des/Assembly Bottom")
	)
	(footprint ""
		(layer "B.Cu")
		(at 120.904 -35.56 -90)
		(property "Reference" "SR616"
			(at 0 0 90)
			(layer "B.SilkS")
			(hide yes)
			(effects
				(font
					(size 1.27 1.27)
				)
				(justify mirror)
			)
		)
		(property "Value" "2K2R2F-GP"
			(at -0.064008 -3.993896 270)
			(unlocked yes)
			(layer "B.Fab")
			(hide yes)
			(effects
				(font
					(size 1.016 1.016)
					(thickness 0.1524)
				)
				(justify mirror)
			)
		)
		(property "Device Type" "R402H16"
			(at -0.064008 -5.517896 270)
			(unlocked yes)
			(layer "B.Fab")
			(hide yes)
			(effects
				(font
					(size 1.016 1.016)
					(thickness 0.1524)
				)
				(justify mirror)
			)
		)
		(duplicate_pad_numbers_are_jumpers no)
		(fp_line
			(start -0.508 -0.9398)
			(end 0.508 -0.9398)
			(stroke
				(width 0.1524)
				(type default)
			)
			(layer "B.SilkS")
		)
		(fp_line
			(start 0.508 -0.9398)
			(end 0.508 0.9398)
			(stroke
				(width 0.1524)
				(type default)
			)
			(layer "B.SilkS")
		)
		(fp_rect
			(start 0.508 0.9398)
			(end -0.508 -0.9398)
			(stroke
				(width 0)
				(type default)
			)
			(fill no)
			(layer "B.CrtYd")
		)
		(fp_rect
			(start 0.508 0.9398)
			(end -0.508 -0.9398)
			(stroke
				(width 0)
				(type default)
			)
			(fill no)
			(layer "B.Fab")
		)
		(pad "1" smd custom
			(at 0 -0.4445 90)
			(size 0.1397 0.1397)
			(layers "B.Cu" "B.Mask" "B.Paste")
			(net "P1V8_C")
			(options
				(clearance outline)
				(anchor circle)
			)
			(primitives
				(gr_poly
					(pts
						(arc
							(start -0.1778 0.2794)
							(mid -0.249642 0.249642)
							(end -0.2794 0.1778)
						)
						(arc
							(start -0.2794 -0.1778)
							(mid -0.249642 -0.249642)
							(end -0.1778 -0.2794)
						)
						(arc
							(start 0.1778 -0.2794)
							(mid 0.249642 -0.249642)
							(end 0.2794 -0.1778)
						)
						(arc
							(start 0.2794 0.1778)
							(mid 0.249642 0.249642)
							(end 0.1778 0.2794)
						)
					)
					(width 0)
					(fill yes)
				)
			)
		)
		(pad "2" smd custom
			(at 0 0.4445 90)
			(size 0.1397 0.1397)
			(layers "B.Cu" "B.Mask" "B.Paste")
			(net "IOC_SCL_0")
			(options
				(clearance outline)
				(anchor circle)
			)
			(primitives
				(gr_poly
					(pts
						(arc
							(start -0.1778 0.2794)
							(mid -0.249642 0.249642)
							(end -0.2794 0.1778)
						)
						(arc
							(start -0.2794 -0.1778)
							(mid -0.249642 -0.249642)
							(end -0.1778 -0.2794)
						)
						(arc
							(start 0.1778 -0.2794)
							(mid 0.249642 -0.249642)
							(end 0.2794 -0.1778)
						)
						(arc
							(start 0.2794 0.1778)
							(mid 0.249642 0.249642)
							(end 0.1778 0.2794)
						)
					)
					(width 0)
					(fill yes)
				)
			)
		)
	)
	(footprint ""
		(layer "B.Cu")
		(at 298.577 -167.64)
		(property "Reference" "TP155"
			(at 0 0 0)
			(layer "B.SilkS")
			(hide yes)
			(effects
				(font
					(size 1.27 1.27)
				)
				(justify mirror)
			)
		)
		(property "Value" "TPAD28"
			(at -0.0127 -1.8034 0)
			(unlocked yes)
			(layer "B.Fab")
			(hide yes)
			(effects
				(font
					(size 1.016 1.016)
					(thickness 0.1524)
				)
				(justify mirror)
			)
		)
		(property "Device Type" "TPAD28"
			(at -0.0127 -3.3274 0)
			(unlocked yes)
			(layer "B.Fab")
			(hide yes)
			(effects
				(font
					(size 1.016 1.016)
					(thickness 0.1524)
				)
				(justify mirror)
			)
		)
		(duplicate_pad_numbers_are_jumpers no)
		(fp_poly
			(pts
				(arc
					(start 0.3556 0)
					(mid -0.3556 0)
					(end 0.3556 0)
				)
			)
			(stroke
				(width 0)
				(type default)
			)
			(fill no)
			(layer "B.CrtYd")
		)
		(fp_poly
			(pts
				(arc
					(start 0.6096 0)
					(mid -0.6096 0)
					(end 0.6096 0)
				)
			)
			(stroke
				(width 0)
				(type default)
			)
			(fill no)
			(layer "B.Fab")
		)
		(pad "1" smd circle
			(at 0 0 180)
			(size 0.7112 0.7112)
			(layers "B.Cu" "B.Mask" "B.Paste")
			(net "TP_BMC_GPIOA7")
		)
	)
	(footprint ""
		(layer "B.Cu")
		(at 98.264726 -54.7116 90)
		(property "Reference" "SC1004"
			(at 0 0 90)
			(layer "B.SilkS")
			(hide yes)
			(effects
				(font
					(size 1.27 1.27)
				)
				(justify mirror)
			)
		)
		(property "Value" "SCD1U16V2KX-3GP"
			(at -1.1811 -2.7051 90)
			(unlocked yes)
			(layer "B.Fab")
			(hide yes)
			(effects
				(font
					(size 1.016 1.016)
					(thickness 0.1524)
				)
				(justify mirror)
			)
		)
		(property "Device Type" "C402H22"
			(at -1.1811 -4.2291 90)
			(unlocked yes)
			(layer "B.Fab")
			(hide yes)
			(effects
				(font
					(size 1.016 1.016)
					(thickness 0.1524)
				)
				(justify mirror)
			)
		)
		(duplicate_pad_numbers_are_jumpers no)
		(fp_rect
			(start 0.4318 0.9525)
			(end -0.4318 -0.9525)
			(stroke
				(width 0)
				(type default)
			)
			(fill no)
			(layer "B.CrtYd")
		)
		(fp_rect
			(start 0.4318 0.9525)
			(end -0.4318 -0.9525)
			(stroke
				(width 0)
				(type default)
			)
			(fill no)
			(layer "B.Fab")
		)
		(pad "1" smd custom
			(at 0 -0.4445 270)
			(size 0.1524 0.1524)
			(layers "B.Cu" "B.Mask" "B.Paste")
			(net "P1V8_C")
			(options
				(clearance outline)
				(anchor circle)
			)
			(primitives
				(gr_poly
					(pts
						(arc
							(start 0.3048 0.2032)
							(mid 0.275042 0.275042)
							(end 0.2032 0.3048)
						)
						(arc
							(start -0.2032 0.3048)
							(mid -0.275042 0.275042)
							(end -0.3048 0.2032)
						)
						(arc
							(start -0.3048 -0.2032)
							(mid -0.275042 -0.275042)
							(end -0.2032 -0.3048)
						)
						(arc
							(start 0.2032 -0.3048)
							(mid 0.275042 -0.275042)
							(end 0.3048 -0.2032)
						)
					)
					(width 0)
					(fill yes)
				)
			)
		)
		(pad "2" smd custom
			(at 0 0.4445 270)
			(size 0.1524 0.1524)
			(layers "B.Cu" "B.Mask" "B.Paste")
			(net "GND")
			(options
				(clearance outline)
				(anchor circle)
			)
			(primitives
				(gr_poly
					(pts
						(arc
							(start 0.3048 0.2032)
							(mid 0.275042 0.275042)
							(end 0.2032 0.3048)
						)
						(arc
							(start -0.2032 0.3048)
							(mid -0.275042 0.275042)
							(end -0.3048 0.2032)
						)
						(arc
							(start -0.3048 -0.2032)
							(mid -0.275042 -0.275042)
							(end -0.2032 -0.3048)
						)
						(arc
							(start 0.2032 -0.3048)
							(mid 0.275042 -0.275042)
							(end 0.3048 -0.2032)
						)
					)
					(width 0)
					(fill yes)
				)
			)
		)
	)
	(footprint ""
		(layer "B.Cu")
		(at 102.997 -228.981 -90)
		(property "Reference" "R665"
			(at 0 0 90)
			(layer "B.SilkS")
			(hide yes)
			(effects
				(font
					(size 1.27 1.27)
				)
				(justify mirror)
			)
		)
		(property "Value" "0R2J-2-GP"
			(at -0.064008 -3.993896 270)
			(unlocked yes)
			(layer "B.Fab")
			(hide yes)
			(effects
				(font
					(size 1.016 1.016)
					(thickness 0.1524)
				)
				(justify mirror)
			)
		)
		(property "Device Type" "R402H16"
			(at -0.064008 -5.517896 270)
			(unlocked yes)
			(layer "B.Fab")
			(hide yes)
			(effects
				(font
					(size 1.016 1.016)
					(thickness 0.1524)
				)
				(justify mirror)
			)
		)
		(duplicate_pad_numbers_are_jumpers no)
		(fp_line
			(start -0.508 -0.9398)
			(end 0.508 -0.9398)
			(stroke
				(width 0.1524)
				(type default)
			)
			(layer "B.SilkS")
		)
		(fp_line
			(start 0.508 -0.9398)
			(end 0.508 0.9398)
			(stroke
				(width 0.1524)
				(type default)
			)
			(layer "B.SilkS")
		)
		(fp_rect
			(start 0.508 0.9398)
			(end -0.508 -0.9398)
			(stroke
				(width 0)
				(type default)
			)
			(fill no)
			(layer "B.CrtYd")
		)
		(fp_rect
			(start 0.508 0.9398)
			(end -0.508 -0.9398)
			(stroke
				(width 0)
				(type default)
			)
			(fill no)
			(layer "B.Fab")
		)
		(pad "1" smd custom
			(at 0 -0.4445 90)
			(size 0.1397 0.1397)
			(layers "B.Cu" "B.Mask" "B.Paste")
			(net "SAS_FAULT_LED3")
			(options
				(clearance outline)
				(anchor circle)
			)
			(primitives
				(gr_poly
					(pts
						(arc
							(start -0.1778 0.2794)
							(mid -0.249642 0.249642)
							(end -0.2794 0.1778)
						)
						(arc
							(start -0.2794 -0.1778)
							(mid -0.249642 -0.249642)
							(end -0.1778 -0.2794)
						)
						(arc
							(start 0.1778 -0.2794)
							(mid 0.249642 -0.249642)
							(end 0.2794 -0.1778)
						)
						(arc
							(start 0.2794 0.1778)
							(mid 0.249642 0.249642)
							(end 0.1778 0.2794)
						)
					)
					(width 0)
					(fill yes)
				)
			)
		)
		(pad "2" smd custom
			(at 0 0.4445 90)
			(size 0.1397 0.1397)
			(layers "B.Cu" "B.Mask" "B.Paste")
			(net "SAS_HDD_LED_3")
			(options
				(clearance outline)
				(anchor circle)
			)
			(primitives
				(gr_poly
					(pts
						(arc
							(start -0.1778 0.2794)
							(mid -0.249642 0.249642)
							(end -0.2794 0.1778)
						)
						(arc
							(start -0.2794 -0.1778)
							(mid -0.249642 -0.249642)
							(end -0.1778 -0.2794)
						)
						(arc
							(start 0.1778 -0.2794)
							(mid 0.249642 -0.249642)
							(end 0.2794 -0.1778)
						)
						(arc
							(start 0.2794 0.1778)
							(mid 0.249642 0.249642)
							(end 0.1778 0.2794)
						)
					)
					(width 0)
					(fill yes)
				)
			)
		)
	)
	(footprint ""
		(layer "B.Cu")
		(at 255.651 -19.431)
		(property "Reference" "C332"
			(at 0 0 0)
			(layer "B.SilkS")
			(hide yes)
			(effects
				(font
					(size 1.27 1.27)
				)
				(justify mirror)
			)
		)
		(property "Value" "SCD1U16V2JX-1-GP"
			(at -1.1811 -2.7051 0)
			(unlocked yes)
			(layer "B.Fab")
			(hide yes)
			(effects
				(font
					(size 1.016 1.016)
					(thickness 0.1524)
				)
				(justify mirror)
			)
		)
		(property "Device Type" "C402H22"
			(at -1.1811 -4.2291 0)
			(unlocked yes)
			(layer "B.Fab")
			(hide yes)
			(effects
				(font
					(size 1.016 1.016)
					(thickness 0.1524)
				)
				(justify mirror)
			)
		)
		(duplicate_pad_numbers_are_jumpers no)
		(fp_rect
			(start 0.4318 0.9525)
			(end -0.4318 -0.9525)
			(stroke
				(width 0)
				(type default)
			)
			(fill no)
			(layer "B.CrtYd")
		)
		(fp_rect
			(start 0.4318 0.9525)
			(end -0.4318 -0.9525)
			(stroke
				(width 0)
				(type default)
			)
			(fill no)
			(layer "B.Fab")
		)
		(pad "1" smd custom
			(at 0 -0.4445 180)
			(size 0.1524 0.1524)
			(layers "B.Cu" "B.Mask" "B.Paste")
			(net "P5V_STBY")
			(options
				(clearance outline)
				(anchor circle)
			)
			(primitives
				(gr_poly
					(pts
						(arc
							(start 0.3048 0.2032)
							(mid 0.275042 0.275042)
							(end 0.2032 0.3048)
						)
						(arc
							(start -0.2032 0.3048)
							(mid -0.275042 0.275042)
							(end -0.3048 0.2032)
						)
						(arc
							(start -0.3048 -0.2032)
							(mid -0.275042 -0.275042)
							(end -0.2032 -0.3048)
						)
						(arc
							(start 0.2032 -0.3048)
							(mid 0.275042 -0.275042)
							(end 0.3048 -0.2032)
						)
					)
					(width 0)
					(fill yes)
				)
			)
		)
		(pad "2" smd custom
			(at 0 0.4445 180)
			(size 0.1524 0.1524)
			(layers "B.Cu" "B.Mask" "B.Paste")
			(net "GND")
			(options
				(clearance outline)
				(anchor circle)
			)
			(primitives
				(gr_poly
					(pts
						(arc
							(start 0.3048 0.2032)
							(mid 0.275042 0.275042)
							(end 0.2032 0.3048)
						)
						(arc
							(start -0.2032 0.3048)
							(mid -0.275042 0.275042)
							(end -0.3048 0.2032)
						)
						(arc
							(start -0.3048 -0.2032)
							(mid -0.275042 -0.275042)
							(end -0.2032 -0.3048)
						)
						(arc
							(start 0.2032 -0.3048)
							(mid 0.275042 -0.275042)
							(end 0.3048 -0.2032)
						)
					)
					(width 0)
					(fill yes)
				)
			)
		)
	)
	(footprint ""
		(layer "B.Cu")
		(at 323.342 -177.8)
		(property "Reference" "R5771"
			(at 0 0 0)
			(layer "B.SilkS")
			(hide yes)
			(effects
				(font
					(size 1.27 1.27)
				)
				(justify mirror)
			)
		)
		(property "Value" "1KR2F-3-GP"
			(at -0.064008 -3.993896 0)
			(unlocked yes)
			(layer "B.Fab")
			(hide yes)
			(effects
				(font
					(size 1.016 1.016)
					(thickness 0.1524)
				)
				(justify mirror)
			)
		)
		(property "Device Type" "R402H16"
			(at -0.064008 -5.517896 0)
			(unlocked yes)
			(layer "B.Fab")
			(hide yes)
			(effects
				(font
					(size 1.016 1.016)
					(thickness 0.1524)
				)
				(justify mirror)
			)
		)
		(duplicate_pad_numbers_are_jumpers no)
		(fp_line
			(start -0.508 -0.9398)
			(end 0.508 -0.9398)
			(stroke
				(width 0.1524)
				(type default)
			)
			(layer "B.SilkS")
		)
		(fp_line
			(start 0.508 -0.9398)
			(end 0.508 0.9398)
			(stroke
				(width 0.1524)
				(type default)
			)
			(layer "B.SilkS")
		)
		(fp_rect
			(start 0.508 0.9398)
			(end -0.508 -0.9398)
			(stroke
				(width 0)
				(type default)
			)
			(fill no)
			(layer "B.CrtYd")
		)
		(fp_rect
			(start 0.508 0.9398)
			(end -0.508 -0.9398)
			(stroke
				(width 0)
				(type default)
			)
			(fill no)
			(layer "B.Fab")
		)
		(pad "1" smd custom
			(at 0 -0.4445 180)
			(size 0.1397 0.1397)
			(layers "B.Cu" "B.Mask" "B.Paste")
			(net "ADC_P5V_STBY")
			(options
				(clearance outline)
				(anchor circle)
			)
			(primitives
				(gr_poly
					(pts
						(arc
							(start -0.1778 0.2794)
							(mid -0.249642 0.249642)
							(end -0.2794 0.1778)
						)
						(arc
							(start -0.2794 -0.1778)
							(mid -0.249642 -0.249642)
							(end -0.1778 -0.2794)
						)
						(arc
							(start 0.1778 -0.2794)
							(mid 0.249642 -0.249642)
							(end 0.2794 -0.1778)
						)
						(arc
							(start 0.2794 0.1778)
							(mid 0.249642 0.249642)
							(end 0.1778 0.2794)
						)
					)
					(width 0)
					(fill yes)
				)
			)
		)
		(pad "2" smd custom
			(at 0 0.4445 180)
			(size 0.1397 0.1397)
			(layers "B.Cu" "B.Mask" "B.Paste")
			(net "GND")
			(options
				(clearance outline)
				(anchor circle)
			)
			(primitives
				(gr_poly
					(pts
						(arc
							(start -0.1778 0.2794)
							(mid -0.249642 0.249642)
							(end -0.2794 0.1778)
						)
						(arc
							(start -0.2794 -0.1778)
							(mid -0.249642 -0.249642)
							(end -0.1778 -0.2794)
						)
						(arc
							(start 0.1778 -0.2794)
							(mid 0.249642 -0.249642)
							(end 0.2794 -0.1778)
						)
						(arc
							(start 0.2794 0.1778)
							(mid 0.249642 0.249642)
							(end 0.1778 0.2794)
						)
					)
					(width 0)
					(fill yes)
				)
			)
		)
	)
	(footprint ""
		(layer "B.Cu")
		(at 78.105 -74.041 180)
		(property "Reference" "PC223"
			(at 0 0 0)
			(layer "B.SilkS")
			(hide yes)
			(effects
				(font
					(size 1.27 1.27)
				)
				(justify mirror)
			)
		)
		(property "Value" "SCD1U50V3KX-GP"
			(at 0 -2.8194 180)
			(unlocked yes)
			(layer "B.Fab")
			(hide yes)
			(effects
				(font
					(size 1.016 1.016)
					(thickness 0.1524)
				)
				(justify mirror)
			)
		)
		(property "Device Type" "C603H36"
			(at 0 -4.3434 180)
			(unlocked yes)
			(layer "B.Fab")
			(hide yes)
			(effects
				(font
					(size 1.016 1.016)
					(thickness 0.1524)
				)
				(justify mirror)
			)
		)
		(duplicate_pad_numbers_are_jumpers no)
		(fp_line
			(start -0.508 0)
			(end 0.508 0)
			(stroke
				(width 0.2032)
				(type default)
			)
			(layer "B.SilkS")
		)
		(fp_rect
			(start 0.5842 1.3335)
			(end -0.5842 -1.3335)
			(stroke
				(width 0)
				(type default)
			)
			(fill no)
			(layer "B.CrtYd")
		)
		(fp_rect
			(start 0.5842 1.3335)
			(end -0.5842 -1.3335)
			(stroke
				(width 0)
				(type default)
			)
			(fill no)
			(layer "B.Fab")
		)
		(pad "1" smd custom
			(at 0 -0.762)
			(size 0.2159 0.2159)
			(layers "B.Cu" "B.Mask" "B.Paste")
			(net "P1V8_C")
			(options
				(clearance outline)
				(anchor circle)
			)
			(primitives
				(gr_poly
					(pts
						(arc
							(start -0.3302 0.4318)
							(mid -0.402042 0.402042)
							(end -0.4318 0.3302)
						)
						(arc
							(start -0.4318 -0.3302)
							(mid -0.402042 -0.402042)
							(end -0.3302 -0.4318)
						)
						(arc
							(start 0.3302 -0.4318)
							(mid 0.402042 -0.402042)
							(end 0.4318 -0.3302)
						)
						(arc
							(start 0.4318 0.3302)
							(mid 0.402042 0.402042)
							(end 0.3302 0.4318)
						)
					)
					(width 0)
					(fill yes)
				)
			)
		)
		(pad "2" smd custom
			(at 0 0.762)
			(size 0.2159 0.2159)
			(layers "B.Cu" "B.Mask" "B.Paste")
			(net "GND")
			(options
				(clearance outline)
				(anchor circle)
			)
			(primitives
				(gr_poly
					(pts
						(arc
							(start -0.3302 0.4318)
							(mid -0.402042 0.402042)
							(end -0.4318 0.3302)
						)
						(arc
							(start -0.4318 -0.3302)
							(mid -0.402042 -0.402042)
							(end -0.3302 -0.4318)
						)
						(arc
							(start 0.3302 -0.4318)
							(mid 0.402042 -0.402042)
							(end 0.4318 -0.3302)
						)
						(arc
							(start 0.4318 0.3302)
							(mid 0.402042 0.402042)
							(end 0.3302 0.4318)
						)
					)
					(width 0)
					(fill yes)
				)
			)
		)
	)
	(footprint ""
		(layer "B.Cu")
		(at 90.913966 -32.639 -90)
		(property "Reference" "SC958"
			(at 0 0 90)
			(layer "B.SilkS")
			(hide yes)
			(effects
				(font
					(size 1.27 1.27)
				)
				(justify mirror)
			)
		)
		(property "Value" "SC1U6D3V1MX-GP"
			(at -1.9177 2.0193 270)
			(unlocked yes)
			(layer "B.Fab")
			(hide yes)
			(effects
				(font
					(size 1.016 1.016)
					(thickness 0.1524)
				)
				(justify mirror)
			)
		)
		(property "Device Type" "C0201H14"
			(at -1.9177 0.4953 270)
			(unlocked yes)
			(layer "B.Fab")
			(hide yes)
			(effects
				(font
					(size 1.016 1.016)
					(thickness 0.1524)
				)
				(justify mirror)
			)
		)
		(duplicate_pad_numbers_are_jumpers no)
		(fp_rect
			(start 0.1524 0.3048)
			(end -0.1524 -0.3048)
			(stroke
				(width 0)
				(type default)
			)
			(fill no)
			(layer "B.CrtYd")
		)
		(fp_poly
			(pts
				(xy 0.2794 0.6477) (xy 0.2794 -0.6477) (xy -0.2794 -0.6477) (xy -0.2794 -0.1905) (xy -0.1524 -0.1905)
				(xy -0.1524 -0.3048) (xy 0.1524 -0.3048) (xy 0.1524 0.3048) (xy -0.1524 0.3048) (xy -0.1524 -0.1778)
				(xy -0.2794 -0.1778) (xy -0.2794 0.6477)
			)
			(stroke
				(width 0)
				(type default)
			)
			(fill no)
			(layer "B.CrtYd")
		)
		(fp_rect
			(start 0.2794 0.6477)
			(end -0.2794 -0.6477)
			(stroke
				(width 0)
				(type default)
			)
			(fill no)
			(layer "B.Fab")
		)
		(pad "1" smd custom
			(at 0 -0.2794 90)
			(size 0.0762 0.0762)
			(layers "B.Cu" "B.Mask" "B.Paste")
			(net "SAS0_AVDD")
			(options
				(clearance outline)
				(anchor circle)
			)
			(primitives
				(gr_poly
					(pts
						(arc
							(start 0.1524 0.127)
							(mid 0.137521 0.162921)
							(end 0.1016 0.1778)
						)
						(arc
							(start -0.1016 0.1778)
							(mid -0.137521 0.162921)
							(end -0.1524 0.127)
						)
						(arc
							(start -0.1524 -0.127)
							(mid -0.137521 -0.162921)
							(end -0.1016 -0.1778)
						)
						(arc
							(start 0.1016 -0.1778)
							(mid 0.137521 -0.162921)
							(end 0.1524 -0.127)
						)
					)
					(width 0)
					(fill yes)
				)
			)
		)
		(pad "2" smd custom
			(at 0 0.2794 90)
			(size 0.0762 0.0762)
			(layers "B.Cu" "B.Mask" "B.Paste")
			(net "GND")
			(options
				(clearance outline)
				(anchor circle)
			)
			(primitives
				(gr_poly
					(pts
						(arc
							(start 0.1524 0.127)
							(mid 0.137521 0.162921)
							(end 0.1016 0.1778)
						)
						(arc
							(start -0.1016 0.1778)
							(mid -0.137521 0.162921)
							(end -0.1524 0.127)
						)
						(arc
							(start -0.1524 -0.127)
							(mid -0.137521 -0.162921)
							(end -0.1016 -0.1778)
						)
						(arc
							(start 0.1016 -0.1778)
							(mid 0.137521 -0.162921)
							(end 0.1524 -0.127)
						)
					)
					(width 0)
					(fill yes)
				)
			)
		)
	)
)
